(kicad_pcb
	(version 20241229)
	(generator "pcbnew")
	(generator_version "9.0")
	(general
		(thickness 1.61)
		(legacy_teardrops no)
	)
	(paper "A3")
	(title_block
		(title "RDIMM DDR5 Tester")
		(date "2026-05-21")
		(rev "2.2.0")
		(company "Antmicro")
		(comment 9 "footprints 174-178 of 796")
	)
	(layers
		(0 "F.Cu" signal)
		(4 "In1.Cu" power)
		(6 "In2.Cu" mixed)
		(8 "In3.Cu" power)
		(10 "In4.Cu" mixed)
		(12 "In5.Cu" power)
		(14 "In6.Cu" mixed)
		(16 "In7.Cu" power)
		(18 "In8.Cu" power)
		(20 "In9.Cu" mixed)
		(22 "In10.Cu" power)
		(2 "B.Cu" signal)
		(9 "F.Adhes" user "F.Adhesive")
		(11 "B.Adhes" user "B.Adhesive")
		(13 "F.Paste" user)
		(15 "B.Paste" user)
		(5 "F.SilkS" user "F.Silkscreen")
		(7 "B.SilkS" user "B.Silkscreen")
		(1 "F.Mask" user)
		(3 "B.Mask" user)
		(17 "Dwgs.User" user "User.Drawings")
		(19 "Cmts.User" user "User.Comments")
		(21 "Eco1.User" user "User.Eco1")
		(23 "Eco2.User" user "User.Eco2")
		(25 "Edge.Cuts" user)
		(27 "Margin" user)
		(31 "F.CrtYd" user "F.Courtyard")
		(29 "B.CrtYd" user "B.Courtyard")
		(35 "F.Fab" user)
		(33 "B.Fab" user)
	)
	(footprint "antmicro-footprints:R_0402_1005Metric"
		(layer "F.Cu")
		(at 150.424499 173.249 -90)
		(descr "Resistor SMD 0402")
		(tags "resistor SMD 0402")
		(property "Reference" "R94"
			(at 0.921 -0.485501 90)
			(layer "F.SilkS")
			(effects
				(font
					(size 0.7 0.7)
					(thickness 0.15)
				)
				(justify right bottom)
			)
		)
		(property "Value" "R_4k7_0402"
			(at -1.011843 1.772047 90)
			(layer "F.Fab")
			(effects
				(font
					(size 0.7 0.7)
					(thickness 0.15)
				)
				(justify right bottom)
			)
		)
		(property "Datasheet" "https://www.bourns.com/docs/product-datasheets/cr.pdf"
			(at 0 0 270)
			(layer "F.Fab")
			(hide yes)
			(effects
				(font
					(size 1.27 1.27)
					(thickness 0.15)
				)
			)
		)
		(property "Manufacturer" "Bourns"
			(at 0 0 270)
			(unlocked yes)
			(layer "F.Fab")
			(hide yes)
			(effects
				(font
					(size 1 1)
					(thickness 0.15)
				)
			)
		)
		(property "MPN" "CR0402-FX-4701GLF"
			(at 0 0 270)
			(unlocked yes)
			(layer "F.Fab")
			(hide yes)
			(effects
				(font
					(size 1 1)
					(thickness 0.15)
				)
			)
		)
		(property "Val" "4k7"
			(at 0 0 270)
			(unlocked yes)
			(layer "F.Fab")
			(hide yes)
			(effects
				(font
					(size 1 1)
					(thickness 0.15)
				)
			)
		)
		(property "License" "Apache-2.0"
			(at 0 0 270)
			(unlocked yes)
			(layer "F.Fab")
			(hide yes)
			(effects
				(font
					(size 1 1)
					(thickness 0.15)
				)
			)
		)
		(property "Author" "Antmicro"
			(at 0 0 270)
			(unlocked yes)
			(layer "F.Fab")
			(hide yes)
			(effects
				(font
					(size 1 1)
					(thickness 0.15)
				)
			)
		)
		(property "Tolerance" "1%"
			(at 0 0 270)
			(unlocked yes)
			(layer "F.Fab")
			(hide yes)
			(effects
				(font
					(size 1 1)
					(thickness 0.15)
				)
			)
		)
		(sheetname "/Debug FTDI + VNA/")
		(sheetfile "debug-ftdi.kicad_sch")
		(attr smd)
		(fp_rect
			(start -0.925 -0.47)
			(end 0.925 0.47)
			(stroke
				(width 0.05)
				(type default)
			)
			(fill no)
			(layer "F.CrtYd")
		)
		(fp_rect
			(start -0.5 -0.25)
			(end 0.5 0.25)
			(stroke
				(width 0.15)
				(type solid)
			)
			(fill no)
			(layer "F.Fab")
		)
		(fp_text user "Author: Antmicro"
			(at -0.95 4.169 270)
			(layer "F.Fab")
			(effects
				(font
					(size 0.7 0.7)
					(thickness 0.15)
				)
				(justify left bottom)
			)
		)
		(fp_text user "${REFERENCE}"
			(at -0.95 3.168 270)
			(layer "F.Fab")
			(effects
				(font
					(size 0.7 0.7)
					(thickness 0.15)
				)
				(justify left bottom)
			)
		)
		(fp_text user "License: Apache-2.0"
			(at -0.95 5.169 270)
			(layer "F.Fab")
			(effects
				(font
					(size 0.7 0.7)
					(thickness 0.15)
				)
				(justify left bottom)
			)
		)
		(pad "1" smd roundrect
			(at -0.48 0 270)
			(size 0.59 0.64)
			(layers "F.Cu" "F.Mask" "F.Paste")
			(roundrect_rratio 0.25)
			(net 38 "+3V3_AON")
			(pintype "passive")
		)
		(pad "2" smd roundrect
			(at 0.48 0 270)
			(size 0.59 0.64)
			(layers "F.Cu" "F.Mask" "F.Paste")
			(roundrect_rratio 0.25)
			(net 526 "/Debug FTDI + VNA/FTDI.SCL")
			(pintype "passive")
		)
	)
	(footprint "antmicro-footprints:R_0402_1005Metric"
		(layer "F.Cu")
		(at 115.098 112.72 -90)
		(descr "Resistor SMD 0402")
		(tags "resistor SMD 0402")
		(property "Reference" "R13"
			(at -3.07 -0.452 90)
			(layer "F.SilkS")
			(effects
				(font
					(size 0.7 0.7)
					(thickness 0.15)
				)
				(justify right bottom)
			)
		)
		(property "Value" "R_330R_0402"
			(at -1.011843 1.772047 90)
			(layer "F.Fab")
			(effects
				(font
					(size 0.7 0.7)
					(thickness 0.15)
				)
				(justify right bottom)
			)
		)
		(property "Datasheet" "https://www.bourns.com/docs/product-datasheets/cr.pdf"
			(at 0 0 270)
			(layer "F.Fab")
			(hide yes)
			(effects
				(font
					(size 1.27 1.27)
					(thickness 0.15)
				)
			)
		)
		(property "Manufacturer" "Bourns"
			(at 0 0 270)
			(unlocked yes)
			(layer "F.Fab")
			(hide yes)
			(effects
				(font
					(size 1 1)
					(thickness 0.15)
				)
			)
		)
		(property "MPN" "CR0402-FX-3300GLF"
			(at 0 0 270)
			(unlocked yes)
			(layer "F.Fab")
			(hide yes)
			(effects
				(font
					(size 1 1)
					(thickness 0.15)
				)
			)
		)
		(property "Val" "330R"
			(at 0 0 270)
			(unlocked yes)
			(layer "F.Fab")
			(hide yes)
			(effects
				(font
					(size 1 1)
					(thickness 0.15)
				)
			)
		)
		(property "License" "Apache-2.0"
			(at 0 0 270)
			(unlocked yes)
			(layer "F.Fab")
			(hide yes)
			(effects
				(font
					(size 1 1)
					(thickness 0.15)
				)
			)
		)
		(property "Author" "Antmicro"
			(at 0 0 270)
			(unlocked yes)
			(layer "F.Fab")
			(hide yes)
			(effects
				(font
					(size 1 1)
					(thickness 0.15)
				)
			)
		)
		(property "Tolerance" "1%"
			(at 0 0 270)
			(unlocked yes)
			(layer "F.Fab")
			(hide yes)
			(effects
				(font
					(size 1 1)
					(thickness 0.15)
				)
			)
		)
		(sheetname "/FPGA Config/")
		(sheetfile "fpga-config.kicad_sch")
		(attr smd)
		(fp_rect
			(start -0.925 -0.47)
			(end 0.925 0.47)
			(stroke
				(width 0.05)
				(type default)
			)
			(fill no)
			(layer "F.CrtYd")
		)
		(fp_rect
			(start -0.5 -0.25)
			(end 0.5 0.25)
			(stroke
				(width 0.15)
				(type solid)
			)
			(fill no)
			(layer "F.Fab")
		)
		(fp_text user "Author: Antmicro"
			(at -0.95 4.169 270)
			(layer "F.Fab")
			(effects
				(font
					(size 0.7 0.7)
					(thickness 0.15)
				)
				(justify left bottom)
			)
		)
		(fp_text user "License: Apache-2.0"
			(at -0.95 5.169 270)
			(layer "F.Fab")
			(effects
				(font
					(size 0.7 0.7)
					(thickness 0.15)
				)
				(justify left bottom)
			)
		)
		(fp_text user "${REFERENCE}"
			(at -0.95 3.168 270)
			(layer "F.Fab")
			(effects
				(font
					(size 0.7 0.7)
					(thickness 0.15)
				)
				(justify left bottom)
			)
		)
		(pad "1" smd roundrect
			(at -0.48 0 270)
			(size 0.59 0.64)
			(layers "F.Cu" "F.Mask" "F.Paste")
			(roundrect_rratio 0.25)
			(net 784 "Net-(D2-C)")
			(pintype "passive")
		)
		(pad "2" smd roundrect
			(at 0.48 0 270)
			(size 0.59 0.64)
			(layers "F.Cu" "F.Mask" "F.Paste")
			(roundrect_rratio 0.25)
			(net 270 "Net-(Q2-D)")
			(pintype "passive")
		)
	)
	(footprint "antmicro-footprints:C_0603_1608Metric"
		(layer "F.Cu")
		(at 251.337998 128.389 -90)
		(descr "Capacitor SMD 0603")
		(tags "capacitor 0603")
		(property "Reference" "C181"
			(at -1.389 0.787998 90)
			(layer "F.SilkS")
			(effects
				(font
					(size 0.7 0.7)
					(thickness 0.15)
				)
				(justify right bottom)
			)
		)
		(property "Value" "C_1u_25V_0603"
			(at -1.42757 1.770288 90)
			(layer "F.Fab")
			(effects
				(font
					(size 0.7 0.7)
					(thickness 0.15)
				)
				(justify right bottom)
			)
		)
		(property "Datasheet" "https://product.samsungsem.com/mlcc/CL10A105KA8NNN.do"
			(at 0 0 270)
			(layer "F.Fab")
			(hide yes)
			(effects
				(font
					(size 1.27 1.27)
					(thickness 0.15)
				)
			)
		)
		(property "Manufacturer" "Samsung Electro-Mechanics"
			(at 0 0 270)
			(unlocked yes)
			(layer "F.Fab")
			(hide yes)
			(effects
				(font
					(size 1 1)
					(thickness 0.15)
				)
			)
		)
		(property "MPN" "CL10A105KA8NNNC"
			(at 0 0 270)
			(unlocked yes)
			(layer "F.Fab")
			(hide yes)
			(effects
				(font
					(size 1 1)
					(thickness 0.15)
				)
			)
		)
		(property "Val" "1u"
			(at 0 0 270)
			(unlocked yes)
			(layer "F.Fab")
			(hide yes)
			(effects
				(font
					(size 1 1)
					(thickness 0.15)
				)
			)
		)
		(property "License" "Apache-2.0"
			(at 0 0 270)
			(unlocked yes)
			(layer "F.Fab")
			(hide yes)
			(effects
				(font
					(size 1 1)
					(thickness 0.15)
				)
			)
		)
		(property "Author" "Antmicro"
			(at 0 0 270)
			(unlocked yes)
			(layer "F.Fab")
			(hide yes)
			(effects
				(font
					(size 1 1)
					(thickness 0.15)
				)
			)
		)
		(property "Voltage" "25V"
			(at 0 0 270)
			(unlocked yes)
			(layer "F.Fab")
			(hide yes)
			(effects
				(font
					(size 1 1)
					(thickness 0.15)
				)
			)
		)
		(property "Dielectric" ""
			(at 0 0 270)
			(unlocked yes)
			(layer "F.Fab")
			(hide yes)
			(effects
				(font
					(size 1 1)
					(thickness 0.15)
				)
			)
		)
		(sheetname "/Supply/")
		(sheetfile "supply.kicad_sch")
		(attr smd)
		(fp_line
			(start -0.15 0.4)
			(end 0.15 0.4)
			(stroke
				(width 0.15)
				(type solid)
			)
			(layer "F.SilkS")
		)
		(fp_line
			(start -0.15 -0.4)
			(end 0.15 -0.4)
			(stroke
				(width 0.15)
				(type solid)
			)
			(layer "F.SilkS")
		)
		(fp_rect
			(start -1.25 -0.65)
			(end 1.25 0.65)
			(stroke
				(width 0.05)
				(type solid)
			)
			(fill no)
			(layer "F.CrtYd")
		)
		(fp_rect
			(start -0.8 -0.4)
			(end 0.8 0.4)
			(stroke
				(width 0.15)
				(type solid)
			)
			(fill no)
			(layer "F.Fab")
		)
		(fp_text user "${REFERENCE}"
			(at -1.682 3.895 270)
			(layer "F.Fab")
			(effects
				(font
					(size 0.7 0.7)
					(thickness 0.15)
				)
				(justify left bottom)
			)
		)
		(fp_text user "Author: Antmicro"
			(at -1.682 4.894 270)
			(layer "F.Fab")
			(effects
				(font
					(size 0.7 0.7)
					(thickness 0.15)
				)
				(justify left bottom)
			)
		)
		(fp_text user "License: Apache-2.0"
			(at -1.682 5.895 270)
			(layer "F.Fab")
			(effects
				(font
					(size 0.7 0.7)
					(thickness 0.15)
				)
				(justify left bottom)
			)
		)
		(pad "1" smd roundrect
			(at -0.7 0 270)
			(size 0.8 1)
			(layers "F.Cu" "F.Mask" "F.Paste")
			(roundrect_rratio 0.2)
			(net 35 "VDC")
			(pintype "passive")
		)
		(pad "2" smd roundrect
			(at 0.7 0 270)
			(size 0.8 1)
			(layers "F.Cu" "F.Mask" "F.Paste")
			(roundrect_rratio 0.2)
			(net 1 "GND")
			(pintype "passive")
		)
	)
	(footprint "antmicro-footprints:R_0402_1005Metric"
		(layer "F.Cu")
		(at 230.2 159.39 -90)
		(descr "Resistor SMD 0402")
		(tags "resistor SMD 0402")
		(property "Reference" "R170"
			(at -1.46 -2.1 90)
			(layer "F.SilkS")
			(effects
				(font
					(size 0.7 0.7)
					(thickness 0.15)
				)
				(justify right bottom)
			)
		)
		(property "Value" "R_10k_0402"
			(at -1.011843 1.772047 90)
			(layer "F.Fab")
			(effects
				(font
					(size 0.7 0.7)
					(thickness 0.15)
				)
				(justify right bottom)
			)
		)
		(property "Datasheet" "https://www.bourns.com/docs/product-datasheets/cr.pdf"
			(at 0 0 270)
			(layer "F.Fab")
			(hide yes)
			(effects
				(font
					(size 1.27 1.27)
					(thickness 0.15)
				)
			)
		)
		(property "MPN" "CR0402-FX-1002GLF"
			(at 0 0 270)
			(unlocked yes)
			(layer "F.Fab")
			(hide yes)
			(effects
				(font
					(size 1 1)
					(thickness 0.15)
				)
			)
		)
		(property "Manufacturer" "Bourns"
			(at 0 0 270)
			(unlocked yes)
			(layer "F.Fab")
			(hide yes)
			(effects
				(font
					(size 1 1)
					(thickness 0.15)
				)
			)
		)
		(property "License" "Apache-2.0"
			(at 0 0 270)
			(unlocked yes)
			(layer "F.Fab")
			(hide yes)
			(effects
				(font
					(size 1 1)
					(thickness 0.15)
				)
			)
		)
		(property "Author" "Antmicro"
			(at 0 0 270)
			(unlocked yes)
			(layer "F.Fab")
			(hide yes)
			(effects
				(font
					(size 1 1)
					(thickness 0.15)
				)
			)
		)
		(property "Val" "10k"
			(at 0 0 270)
			(unlocked yes)
			(layer "F.Fab")
			(hide yes)
			(effects
				(font
					(size 1 1)
					(thickness 0.15)
				)
			)
		)
		(property "Tolerance" "1%"
			(at 0 0 270)
			(unlocked yes)
			(layer "F.Fab")
			(hide yes)
			(effects
				(font
					(size 1 1)
					(thickness 0.15)
				)
			)
		)
		(sheetname "/Supply/")
		(sheetfile "supply.kicad_sch")
		(attr smd)
		(fp_rect
			(start -0.925 -0.47)
			(end 0.925 0.47)
			(stroke
				(width 0.05)
				(type default)
			)
			(fill no)
			(layer "F.CrtYd")
		)
		(fp_rect
			(start -0.5 -0.25)
			(end 0.5 0.25)
			(stroke
				(width 0.15)
				(type solid)
			)
			(fill no)
			(layer "F.Fab")
		)
		(fp_text user "License: Apache-2.0"
			(at -0.95 5.169 270)
			(layer "F.Fab")
			(effects
				(font
					(size 0.7 0.7)
					(thickness 0.15)
				)
				(justify left bottom)
			)
		)
		(fp_text user "Author: Antmicro"
			(at -0.95 4.169 270)
			(layer "F.Fab")
			(effects
				(font
					(size 0.7 0.7)
					(thickness 0.15)
				)
				(justify left bottom)
			)
		)
		(fp_text user "${REFERENCE}"
			(at -0.95 3.168 270)
			(layer "F.Fab")
			(effects
				(font
					(size 0.7 0.7)
					(thickness 0.15)
				)
				(justify left bottom)
			)
		)
		(pad "1" smd roundrect
			(at -0.48 0 270)
			(size 0.59 0.64)
			(layers "F.Cu" "F.Mask" "F.Paste")
			(roundrect_rratio 0.25)
			(net 250 "Net-(Q15-D)")
			(pintype "passive")
		)
		(pad "2" smd roundrect
			(at 0.48 0 270)
			(size 0.59 0.64)
			(layers "F.Cu" "F.Mask" "F.Paste")
			(roundrect_rratio 0.25)
			(net 152 "+5V")
			(pintype "passive")
		)
	)
	(footprint "antmicro-footprints:C_0603_1608Metric"
		(layer "F.Cu")
		(at 215.944999 170.109999)
		(descr "Capacitor SMD 0603")
		(tags "capacitor 0603")
		(property "Reference" "C265"
			(at -4.144999 0.540001 0)
			(layer "F.SilkS")
			(effects
				(font
					(size 0.7 0.7)
					(thickness 0.15)
				)
				(justify left bottom)
			)
		)
		(property "Value" "C_22u_0603"
			(at -1.42757 1.770288 0)
			(layer "F.Fab")
			(effects
				(font
					(size 0.7 0.7)
					(thickness 0.15)
				)
				(justify left bottom)
			)
		)
		(property "Datasheet" "https://www.murata.com/products/productdetail?partno=GRM188R60J226MEA0%23"
			(at 0 0 0)
			(layer "F.Fab")
			(hide yes)
			(effects
				(font
					(size 1.27 1.27)
					(thickness 0.15)
				)
			)
		)
		(property "Manufacturer" "Murata"
			(at 0 0 0)
			(unlocked yes)
			(layer "F.Fab")
			(hide yes)
			(effects
				(font
					(size 1 1)
					(thickness 0.15)
				)
			)
		)
		(property "MPN" "GRM188R60J226MEA0D"
			(at 0 0 0)
			(unlocked yes)
			(layer "F.Fab")
			(hide yes)
			(effects
				(font
					(size 1 1)
					(thickness 0.15)
				)
			)
		)
		(property "Val" "22u"
			(at 0 0 0)
			(unlocked yes)
			(layer "F.Fab")
			(hide yes)
			(effects
				(font
					(size 1 1)
					(thickness 0.15)
				)
			)
		)
		(property "License" "Apache-2.0"
			(at 0 0 0)
			(unlocked yes)
			(layer "F.Fab")
			(hide yes)
			(effects
				(font
					(size 1 1)
					(thickness 0.15)
				)
			)
		)
		(property "Author" "Antmicro"
			(at 0 0 0)
			(unlocked yes)
			(layer "F.Fab")
			(hide yes)
			(effects
				(font
					(size 1 1)
					(thickness 0.15)
				)
			)
		)
		(property "Voltage" ""
			(at 0 0 0)
			(unlocked yes)
			(layer "F.Fab")
			(hide yes)
			(effects
				(font
					(size 1 1)
					(thickness 0.15)
				)
			)
		)
		(property "Dielectric" ""
			(at 0 0 0)
			(unlocked yes)
			(layer "F.Fab")
			(hide yes)
			(effects
				(font
					(size 1 1)
					(thickness 0.15)
				)
			)
		)
		(sheetname "/Supply/DC-DC VCCINT/")
		(sheetfile "dc-dc-vccint.kicad_sch")
		(attr smd)
		(fp_line
			(start -0.15 -0.4)
			(end 0.15 -0.4)
			(stroke
				(width 0.15)
				(type solid)
			)
			(layer "F.SilkS")
		)
		(fp_line
			(start -0.15 0.4)
			(end 0.15 0.4)
			(stroke
				(width 0.15)
				(type solid)
			)
			(layer "F.SilkS")
		)
		(fp_rect
			(start -1.25 -0.65)
			(end 1.25 0.65)
			(stroke
				(width 0.05)
				(type solid)
			)
			(fill no)
			(layer "F.CrtYd")
		)
		(fp_rect
			(start -0.8 -0.4)
			(end 0.8 0.4)
			(stroke
				(width 0.15)
				(type solid)
			)
			(fill no)
			(layer "F.Fab")
		)
		(fp_text user "Author: Antmicro"
			(at -1.682 4.894 0)
			(layer "F.Fab")
			(effects
				(font
					(size 0.7 0.7)
					(thickness 0.15)
				)
				(justify left bottom)
			)
		)
		(fp_text user "${REFERENCE}"
			(at -1.682 3.895 0)
			(layer "F.Fab")
			(effects
				(font
					(size 0.7 0.7)
					(thickness 0.15)
				)
				(justify left bottom)
			)
		)
		(fp_text user "License: Apache-2.0"
			(at -1.682 5.895 0)
			(layer "F.Fab")
			(effects
				(font
					(size 0.7 0.7)
					(thickness 0.15)
				)
				(justify left bottom)
			)
		)
		(pad "1" smd roundrect
			(at -0.7 0)
			(size 0.8 1)
			(layers "F.Cu" "F.Mask" "F.Paste")
			(roundrect_rratio 0.2)
			(net 1 "GND")
			(pintype "passive")
		)
		(pad "2" smd roundrect
			(at 0.7 0)
			(size 0.8 1)
			(layers "F.Cu" "F.Mask" "F.Paste")
			(roundrect_rratio 0.2)
			(net 223 "/Supply/DC-DC VCCINT/0V85_REG0")
			(pintype "passive")
		)
	)
)
